# S9S_MB_2U (Grand Teton) — schematic netlist excerpt (pin names and nets, part order shuffled) for the footprints in the layout excerpt that follows; sources: Cadence DE-HDL packaged netlist, KiCad conversion of 03242023_DA0F0TMBIJ0_F0T_Motherboard_J_brd_V01_OCP.brd

R4129  Q_RES  4.7K 5% CHIP  pkg 0402LF  page 146 : A = P3V3_AUX ; B = PRSNT_CABLE_GPU_B3_ISO_N
R3183  Q_RES  10K 1% CHIP  pkg 0402LF  page 161 : A = P3V3_OCP_V3_2 ; B = PU_OCP_V3_2_WAKE_OE

(kicad_pcb
	(version 20260206)
	(generator "pcbnew")
	(generator_version "10.0")
	(general
		(thickness 1.6)
		(legacy_teardrops no)
	)
	(paper "A4")
	(title_block
		(title "03242023_DA0F0TMBIJ0_F0T_Motherboard_J_brd_V01_OCP.brd")
		(comment 1 "Grand Teton / footprints 1028-1029 of 6105")
	)
	(layers
		(0 "F.Cu" signal "TOP")
		(4 "In1.Cu" signal "GND")
		(6 "In2.Cu" signal "IN1")
		(8 "In3.Cu" signal "GND1")
		(10 "In4.Cu" signal "IN2")
		(12 "In5.Cu" signal "GND2")
		(14 "In6.Cu" signal "IN3")
		(16 "In7.Cu" signal "GND3")
		(18 "In8.Cu" signal "VCC")
		(20 "In9.Cu" signal "VCC1")
		(22 "In10.Cu" signal "GND4")
		(24 "In11.Cu" signal "IN4")
		(26 "In12.Cu" signal "GND5")
		(28 "In13.Cu" signal "IN5")
		(30 "In14.Cu" signal "GND6")
		(32 "In15.Cu" signal "IN6")
		(34 "In16.Cu" signal "GND7")
		(2 "B.Cu" signal "BOTTOM")
		(9 "F.Adhes" user "F.Adhesive")
		(11 "B.Adhes" user "B.Adhesive")
		(13 "F.Paste" user "Package Geometry/Pastemask Top")
		(15 "B.Paste" user "Package Geometry/Pastemask Bottom")
		(5 "F.SilkS" user "Ref Des/Silkscreen Top")
		(7 "B.SilkS" user "Ref Des/Silkscreen Bottom")
		(1 "F.Mask" user "Board Geometry/Soldermask Top")
		(3 "B.Mask" user "Board Geometry/Soldermask Bottom")
		(17 "Dwgs.User" user "User.Drawings")
		(19 "Cmts.User" user "User.Comments")
		(21 "Eco1.User" user "User.Eco1")
		(23 "Eco2.User" user "User.Eco2")
		(25 "Edge.Cuts" user "Board Geometry/Outline")
		(27 "Margin" user)
		(31 "F.CrtYd" user "Package Geometry/Place Bound Top")
		(29 "B.CrtYd" user "Package Geometry/Place Bound Bottom")
		(35 "F.Fab" user "Ref Des/Assembly Top")
		(33 "B.Fab" user "Ref Des/Assembly Bottom")
	)
	(footprint ""
		(layer "F.Cu")
		(at 282.452826 -18.491962 180)
		(property "Reference" "R3183"
			(at 0 0 180)
			(layer "F.SilkS")
			(hide yes)
			(effects
				(font
					(size 1.27 1.27)
				)
			)
		)
		(property "Value" ""
			(at 0 0 180)
			(layer "F.Fab")
			(effects
				(font
					(size 1.27 1.27)
				)
			)
		)
		(duplicate_pad_numbers_are_jumpers no)
		(fp_line
			(start 0.7874 0.4064)
			(end -0.7874 0.4064)
			(stroke
				(width 0.1524)
				(type default)
			)
			(layer "F.SilkS")
		)
		(fp_line
			(start 0.7874 -0.4064)
			(end 0.7874 0.4064)
			(stroke
				(width 0.1524)
				(type default)
			)
			(layer "F.SilkS")
		)
		(fp_line
			(start -0.7874 0.4064)
			(end -0.7874 -0.4064)
			(stroke
				(width 0.1524)
				(type default)
			)
			(layer "F.SilkS")
		)
		(fp_line
			(start -0.7874 -0.4064)
			(end 0.7874 -0.4064)
			(stroke
				(width 0.1524)
				(type default)
			)
			(layer "F.SilkS")
		)
		(fp_line
			(start 0.67945 0.3048)
			(end 0.120396 0.3048)
			(stroke
				(width 0.1)
				(type default)
			)
			(layer "F.Fab")
		)
		(fp_line
			(start 0.67945 -0.3048)
			(end 0.67945 0.3048)
			(stroke
				(width 0.1)
				(type default)
			)
			(layer "F.Fab")
		)
		(fp_line
			(start 0.12065 -0.2794)
			(end 0.12065 -0.3048)
			(stroke
				(width 0.1)
				(type default)
			)
			(layer "F.Fab")
		)
		(fp_line
			(start 0.12065 -0.3048)
			(end 0.67945 -0.3048)
			(stroke
				(width 0.1)
				(type default)
			)
			(layer "F.Fab")
		)
		(fp_line
			(start 0.120396 0.3048)
			(end 0.120396 0.2794)
			(stroke
				(width 0.1)
				(type default)
			)
			(layer "F.Fab")
		)
		(fp_line
			(start 0.120396 0.2794)
			(end -0.12065 0.2794)
			(stroke
				(width 0.1)
				(type default)
			)
			(layer "F.Fab")
		)
		(fp_line
			(start -0.12065 0.3048)
			(end -0.67945 0.3048)
			(stroke
				(width 0.1)
				(type default)
			)
			(layer "F.Fab")
		)
		(fp_line
			(start -0.12065 0.2794)
			(end -0.12065 0.3048)
			(stroke
				(width 0.1)
				(type default)
			)
			(layer "F.Fab")
		)
		(fp_line
			(start -0.12065 -0.2794)
			(end 0.12065 -0.2794)
			(stroke
				(width 0.1)
				(type default)
			)
			(layer "F.Fab")
		)
		(fp_line
			(start -0.12065 -0.305054)
			(end -0.12065 -0.2794)
			(stroke
				(width 0.1)
				(type default)
			)
			(layer "F.Fab")
		)
		(fp_line
			(start -0.67945 0.3048)
			(end -0.67945 -0.305054)
			(stroke
				(width 0.1)
				(type default)
			)
			(layer "F.Fab")
		)
		(fp_line
			(start -0.67945 -0.305054)
			(end -0.12065 -0.305054)
			(stroke
				(width 0.1)
				(type default)
			)
			(layer "F.Fab")
		)
		(pad "1" smd circle
			(at -0.40005 0 180)
			(size 0 0)
			(layers "F.Cu" "F.Mask" "F.Paste")
			(net "P3V3_OCP_V3_2")
		)
		(pad "2" smd circle
			(at 0.40005 0 180)
			(size 0 0)
			(layers "F.Cu" "F.Mask" "F.Paste")
			(net "PU_OCP_V3_2_WAKE_OE")
		)
	)
	(footprint ""
		(layer "F.Cu")
		(at 301.45482 -421.41521 90)
		(property "Reference" "R4129"
			(at 0 0 90)
			(layer "F.SilkS")
			(hide yes)
			(effects
				(font
					(size 1.27 1.27)
				)
			)
		)
		(property "Value" ""
			(at 0 0 90)
			(layer "F.Fab")
			(effects
				(font
					(size 1.27 1.27)
				)
			)
		)
		(duplicate_pad_numbers_are_jumpers no)
		(fp_line
			(start 0.7874 -0.4064)
			(end 0.7874 0.4064)
			(stroke
				(width 0.1524)
				(type default)
			)
			(layer "F.SilkS")
		)
		(fp_line
			(start -0.7874 -0.4064)
			(end 0.7874 -0.4064)
			(stroke
				(width 0.1524)
				(type default)
			)
			(layer "F.SilkS")
		)
		(fp_line
			(start 0.7874 0.4064)
			(end -0.7874 0.4064)
			(stroke
				(width 0.1524)
				(type default)
			)
			(layer "F.SilkS")
		)
		(fp_line
			(start -0.7874 0.4064)
			(end -0.7874 -0.4064)
			(stroke
				(width 0.1524)
				(type default)
			)
			(layer "F.SilkS")
		)
		(fp_line
			(start -0.12065 -0.305054)
			(end -0.12065 -0.2794)
			(stroke
				(width 0.1)
				(type default)
			)
			(layer "F.Fab")
		)
		(fp_line
			(start -0.67945 -0.305054)
			(end -0.12065 -0.305054)
			(stroke
				(width 0.1)
				(type default)
			)
			(layer "F.Fab")
		)
		(fp_line
			(start 0.67945 -0.3048)
			(end 0.67945 0.3048)
			(stroke
				(width 0.1)
				(type default)
			)
			(layer "F.Fab")
		)
		(fp_line
			(start 0.12065 -0.3048)
			(end 0.67945 -0.3048)
			(stroke
				(width 0.1)
				(type default)
			)
			(layer "F.Fab")
		)
		(fp_line
			(start 0.12065 -0.2794)
			(end 0.12065 -0.3048)
			(stroke
				(width 0.1)
				(type default)
			)
			(layer "F.Fab")
		)
		(fp_line
			(start -0.12065 -0.2794)
			(end 0.12065 -0.2794)
			(stroke
				(width 0.1)
				(type default)
			)
			(layer "F.Fab")
		)
		(fp_line
			(start 0.120396 0.2794)
			(end -0.12065 0.2794)
			(stroke
				(width 0.1)
				(type default)
			)
			(layer "F.Fab")
		)
		(fp_line
			(start -0.12065 0.2794)
			(end -0.12065 0.3048)
			(stroke
				(width 0.1)
				(type default)
			)
			(layer "F.Fab")
		)
		(fp_line
			(start 0.67945 0.3048)
			(end 0.120396 0.3048)
			(stroke
				(width 0.1)
				(type default)
			)
			(layer "F.Fab")
		)
		(fp_line
			(start 0.120396 0.3048)
			(end 0.120396 0.2794)
			(stroke
				(width 0.1)
				(type default)
			)
			(layer "F.Fab")
		)
		(fp_line
			(start -0.12065 0.3048)
			(end -0.67945 0.3048)
			(stroke
				(width 0.1)
				(type default)
			)
			(layer "F.Fab")
		)
		(fp_line
			(start -0.67945 0.3048)
			(end -0.67945 -0.305054)
			(stroke
				(width 0.1)
				(type default)
			)
			(layer "F.Fab")
		)
		(pad "1" smd circle
			(at -0.40005 0 90)
			(size 0 0)
			(layers "F.Cu" "F.Mask" "F.Paste")
			(net "P3V3_AUX")
		)
		(pad "2" smd circle
			(at 0.40005 0 90)
			(size 0 0)
			(layers "F.Cu" "F.Mask" "F.Paste")
			(net "PRSNT_CABLE_GPU_B3_ISO_N")
		)
	)
)
